(kicad_sch (version 20230121) (generator eeschema)

  (paper "A3")

  (title_block
    (title "Data Center RDIMM DDR4 Tester")
    (date "2024-09-30")
    (rev "1.2.4")
    (company "Antmicro Ltd.")
    (comment 1 "www.antmicro.com")
    (comment 2 "Antmicro Ltd")
  )

  (junction (at 179.705 111.76) (diameter 0) (color 0 0 0 0)
  )
  (junction (at 223.52 164.465) (diameter 0) (color 0 0 0 0)
  )
  (junction (at 223.52 126.365) (diameter 0) (color 0 0 0 0)
  )
  (junction (at 179.705 126.365) (diameter 0) (color 0 0 0 0)
  )
  (junction (at 245.745 128.905) (diameter 0) (color 0 0 0 0)
  )
  (junction (at 182.88 128.905) (diameter 0) (color 0 0 0 0)
  )
  (junction (at 223.52 128.905) (diameter 0) (color 0 0 0 0)
  )
  (junction (at 238.125 128.905) (diameter 0) (color 0 0 0 0)
  )
  (junction (at 229.87 128.905) (diameter 0) (color 0 0 0 0)
  )

  (wire (pts (xy 229.87 131.445) (xy 229.87 128.905))
    (stroke (width 0) (type default))
  )
  (wire (pts (xy 182.88 123.19) (xy 182.88 128.905))
    (stroke (width 0) (type default))
  )
  (wire (pts (xy 229.87 128.905) (xy 238.125 128.905))
    (stroke (width 0) (type default))
  )
  (wire (pts (xy 190.5 149.225) (xy 172.72 149.225))
    (stroke (width 0) (type default))
  )
  (wire (pts (xy 190.5 159.385) (xy 172.72 159.385))
    (stroke (width 0) (type default))
  )
  (wire (pts (xy 220.98 164.465) (xy 223.52 164.465))
    (stroke (width 0) (type default))
  )
  (wire (pts (xy 190.5 154.305) (xy 172.72 154.305))
    (stroke (width 0) (type default))
  )
  (wire (pts (xy 223.52 128.905) (xy 229.87 128.905))
    (stroke (width 0) (type default))
  )
  (wire (pts (xy 223.52 111.76) (xy 223.52 126.365))
    (stroke (width 0) (type default))
  )
  (wire (pts (xy 220.98 126.365) (xy 223.52 126.365))
    (stroke (width 0) (type default))
  )
  (wire (pts (xy 245.745 128.905) (xy 253.365 128.905))
    (stroke (width 0) (type default))
  )
  (wire (pts (xy 190.5 144.145) (xy 172.72 144.145))
    (stroke (width 0) (type default))
  )
  (wire (pts (xy 172.72 156.845) (xy 190.5 156.845))
    (stroke (width 0) (type default))
  )
  (wire (pts (xy 190.5 126.365) (xy 179.705 126.365))
    (stroke (width 0) (type default))
  )
  (wire (pts (xy 190.5 136.525) (xy 172.72 136.525))
    (stroke (width 0) (type default))
  )
  (wire (pts (xy 182.88 128.905) (xy 172.72 128.905))
    (stroke (width 0) (type default))
  )
  (wire (pts (xy 253.365 128.905) (xy 253.365 131.445))
    (stroke (width 0) (type default))
  )
  (wire (pts (xy 172.72 146.685) (xy 190.5 146.685))
    (stroke (width 0) (type default))
  )
  (wire (pts (xy 179.705 123.19) (xy 179.705 126.365))
    (stroke (width 0) (type default))
  )
  (wire (pts (xy 172.72 164.465) (xy 190.5 164.465))
    (stroke (width 0) (type default))
  )
  (wire (pts (xy 172.72 151.765) (xy 190.5 151.765))
    (stroke (width 0) (type default))
  )
  (wire (pts (xy 223.52 128.905) (xy 223.52 126.365))
    (stroke (width 0) (type default))
  )
  (wire (pts (xy 238.125 131.445) (xy 238.125 128.905))
    (stroke (width 0) (type default))
  )
  (wire (pts (xy 182.88 111.76) (xy 182.88 118.11))
    (stroke (width 0) (type default))
  )
  (wire (pts (xy 220.98 128.905) (xy 223.52 128.905))
    (stroke (width 0) (type default))
  )
  (wire (pts (xy 182.88 128.905) (xy 190.5 128.905))
    (stroke (width 0) (type default))
  )
  (wire (pts (xy 245.745 128.905) (xy 245.745 131.445))
    (stroke (width 0) (type default))
  )
  (wire (pts (xy 238.125 128.905) (xy 245.745 128.905))
    (stroke (width 0) (type default))
  )
  (wire (pts (xy 179.705 111.76) (xy 179.705 118.11))
    (stroke (width 0) (type default))
  )
  (wire (pts (xy 190.5 133.985) (xy 172.72 133.985))
    (stroke (width 0) (type default))
  )
  (wire (pts (xy 172.72 141.605) (xy 190.5 141.605))
    (stroke (width 0) (type default))
  )
  (wire (pts (xy 223.52 164.465) (xy 223.52 166.37))
    (stroke (width 0) (type default))
  )
  (wire (pts (xy 223.52 111.76) (xy 220.345 111.76))
    (stroke (width 0) (type default))
  )
  (wire (pts (xy 179.705 111.76) (xy 172.72 111.76))
    (stroke (width 0) (type default))
  )
  (wire (pts (xy 179.705 126.365) (xy 172.72 126.365))
    (stroke (width 0) (type default))
  )
  (wire (pts (xy 179.705 111.76) (xy 182.88 111.76))
    (stroke (width 0) (type default))
  )
  (wire (pts (xy 220.98 161.925) (xy 223.52 161.925))
    (stroke (width 0) (type default))
  )
  (wire (pts (xy 223.52 161.925) (xy 223.52 164.465))
    (stroke (width 0) (type default))
  )

  (text "HyperRAM" (at 186.055 104.775 0)
    (effects (font (size 2.9972 2.9972) (thickness 0.5994) bold) (justify left bottom))
  )

  (global_label "HR_DQ1" (shape input) (at 172.72 144.145 180) (fields_autoplaced)
    (effects (font (size 1.27 1.27)) (justify right))
    (property "Intersheetrefs" "${INTERSHEET_REFS}" (at 163.0177 144.0656 0)
      (effects (font (size 1.27 1.27)) (justify right) hide)
    )
  )
  (global_label "HR_RST" (shape input) (at 172.72 126.365 180) (fields_autoplaced)
    (effects (font (size 1.27 1.27)) (justify right))
    (property "Intersheetrefs" "${INTERSHEET_REFS}" (at 163.3806 126.2856 0)
      (effects (font (size 1.27 1.27)) (justify right) hide)
    )
  )
  (global_label "HR_DQ4" (shape input) (at 172.72 151.765 180) (fields_autoplaced)
    (effects (font (size 1.27 1.27)) (justify right))
    (property "Intersheetrefs" "${INTERSHEET_REFS}" (at 163.0177 151.6856 0)
      (effects (font (size 1.27 1.27)) (justify right) hide)
    )
  )
  (global_label "HR_CKP" (shape input) (at 172.72 133.985 180) (fields_autoplaced)
    (effects (font (size 1.27 1.27)) (justify right))
    (property "Intersheetrefs" "${INTERSHEET_REFS}" (at 163.0177 134.0644 0)
      (effects (font (size 1.27 1.27)) (justify right) hide)
    )
  )
  (global_label "HR_DQ5" (shape input) (at 172.72 154.305 180) (fields_autoplaced)
    (effects (font (size 1.27 1.27)) (justify right))
    (property "Intersheetrefs" "${INTERSHEET_REFS}" (at 163.0177 154.2256 0)
      (effects (font (size 1.27 1.27)) (justify right) hide)
    )
  )
  (global_label "HR_CS" (shape input) (at 172.72 128.905 180) (fields_autoplaced)
    (effects (font (size 1.27 1.27)) (justify right))
    (property "Intersheetrefs" "${INTERSHEET_REFS}" (at 164.3482 128.8256 0)
      (effects (font (size 1.27 1.27)) (justify right) hide)
    )
  )
  (global_label "HR_RW" (shape input) (at 172.72 164.465 180) (fields_autoplaced)
    (effects (font (size 1.27 1.27)) (justify right))
    (property "Intersheetrefs" "${INTERSHEET_REFS}" (at 164.1063 164.3856 0)
      (effects (font (size 1.27 1.27)) (justify right) hide)
    )
  )
  (global_label "HR_DQ0" (shape input) (at 172.72 141.605 180) (fields_autoplaced)
    (effects (font (size 1.27 1.27)) (justify right))
    (property "Intersheetrefs" "${INTERSHEET_REFS}" (at 163.0177 141.5256 0)
      (effects (font (size 1.27 1.27)) (justify right) hide)
    )
  )
  (global_label "3V3_SYS" (shape input) (at 220.345 111.76 180) (fields_autoplaced)
    (effects (font (size 1.27 1.27)) (justify right))
    (property "Intersheetrefs" "${INTERSHEET_REFS}" (at 210.0379 111.8394 0)
      (effects (font (size 1.27 1.27)) (justify right) hide)
    )
  )
  (global_label "HR_CKN" (shape input) (at 172.72 136.525 180) (fields_autoplaced)
    (effects (font (size 1.27 1.27)) (justify right))
    (property "Intersheetrefs" "${INTERSHEET_REFS}" (at 162.9572 136.6044 0)
      (effects (font (size 1.27 1.27)) (justify right) hide)
    )
  )
  (global_label "HR_DQ7" (shape input) (at 172.72 159.385 180) (fields_autoplaced)
    (effects (font (size 1.27 1.27)) (justify right))
    (property "Intersheetrefs" "${INTERSHEET_REFS}" (at 163.0177 159.3056 0)
      (effects (font (size 1.27 1.27)) (justify right) hide)
    )
  )
  (global_label "3V3_SYS" (shape input) (at 172.72 111.76 180) (fields_autoplaced)
    (effects (font (size 1.27 1.27)) (justify right))
    (property "Intersheetrefs" "${INTERSHEET_REFS}" (at 162.4129 111.6806 0)
      (effects (font (size 1.27 1.27)) (justify right) hide)
    )
  )
  (global_label "HR_DQ2" (shape input) (at 172.72 146.685 180) (fields_autoplaced)
    (effects (font (size 1.27 1.27)) (justify right))
    (property "Intersheetrefs" "${INTERSHEET_REFS}" (at 163.0177 146.6056 0)
      (effects (font (size 1.27 1.27)) (justify right) hide)
    )
  )
  (global_label "HR_DQ6" (shape input) (at 172.72 156.845 180) (fields_autoplaced)
    (effects (font (size 1.27 1.27)) (justify right))
    (property "Intersheetrefs" "${INTERSHEET_REFS}" (at 163.0177 156.7656 0)
      (effects (font (size 1.27 1.27)) (justify right) hide)
    )
  )
  (global_label "HR_DQ3" (shape input) (at 172.72 149.225 180) (fields_autoplaced)
    (effects (font (size 1.27 1.27)) (justify right))
    (property "Intersheetrefs" "${INTERSHEET_REFS}" (at 163.0177 149.1456 0)
      (effects (font (size 1.27 1.27)) (justify right) hide)
    )
  )

  (symbol (lib_id "antmicroMemory:S27KL0641DABHI023") (at 190.5 126.365 0) (unit 1)
    (in_bom yes) (on_board yes) (dnp no) (fields_autoplaced)
    (property "Reference" "U11" (at 205.74 118.11 0)
      (effects (font (size 1.27 1.27)))
    )
    (property "Value" "S27KL0641DABHI023" (at 205.74 172.72 0)
      (effects (font (size 1.27 1.27) (thickness 0.15)) hide)
    )
    (property "Footprint" "antmicro-footprints:FBGA-25-24_6x8mm_Layout5x5_P1mm" (at 236.22 136.525 0)
      (effects (font (size 1.27 1.27) (thickness 0.15)) (justify left bottom) hide)
    )
    (property "Datasheet" "https://www.mouser.pl/datasheet/2/196/CYPR_S_A0011122227_1-3004854.pdf" (at 236.22 139.065 0)
      (effects (font (size 1.27 1.27) (thickness 0.15)) (justify left bottom) hide)
    )
    (property "Manufacturer" "Cypress Semiconductor" (at 236.22 141.605 0)
      (effects (font (size 1.27 1.27) (thickness 0.15)) (justify left bottom) hide)
    )
    (property "MPN" "S27KL0641DABHI023" (at 205.74 120.65 0)
      (effects (font (size 1.27 1.27) (thickness 0.15)))
    )
    (property "Author" "Antmicro" (at 236.22 146.685 0)
      (effects (font (size 1.27 1.27) (thickness 0.15)) (justify left bottom) hide)
    )
    (property "License" "Apache-2.0" (at 236.22 149.225 0)
      (effects (font (size 1.27 1.27) (thickness 0.15)) (justify left bottom) hide)
    )
    (pin "A2")
    (pin "A3")
    (pin "A4")
    (pin "A5")
    (pin "B1")
    (pin "B2")
    (pin "B3")
    (pin "B4")
    (pin "B5")
    (pin "C1")
    (pin "C2")
    (pin "C3")
    (pin "C4")
    (pin "C5")
    (pin "D1")
    (pin "D2")
    (pin "D3")
    (pin "D4")
    (pin "D5")
    (pin "E1")
    (pin "E2")
    (pin "E3")
    (pin "E4")
    (pin "E5")
    (instances
      (project "data-center-rdimm-ddr4-tester"
        (path ""
          (reference "U11") (unit 1)
        )
      )
    )
  )

  (symbol (lib_id "antmicroCapacitors0603:C_47u_0603") (at 229.87 131.445 270) (unit 1)
    (in_bom yes) (on_board yes) (dnp no)
    (property "Reference" "C102" (at 230.505 132.08 90)
      (effects (font (size 1.524 1.524)) (justify left))
    )
    (property "Value" "C_47u_0603" (at 219.71 151.765 0)
      (effects (font (size 1.27 1.27) (thickness 0.15)) (justify left bottom) hide)
    )
    (property "Footprint" "antmicro-footprints:C_0603_1608Metric" (at 217.17 151.765 0)
      (effects (font (size 1.27 1.27) (thickness 0.15)) (justify left bottom) hide)
    )
    (property "Datasheet" " " (at 214.63 151.765 0)
      (effects (font (size 1.27 1.27) (thickness 0.15)) (justify left bottom) hide)
    )
    (property "Manufacturer" "Murata" (at 209.55 151.765 0)
      (effects (font (size 1.27 1.27) (thickness 0.15)) (justify left bottom) hide)
    )
    (property "MPN" "GRM188R60J476ME15D" (at 212.09 151.765 0)
      (effects (font (size 1.27 1.27) (thickness 0.15)) (justify left bottom) hide)
    )
    (property "Val" "47u" (at 230.505 135.89 90)
      (effects (font (size 1.27 1.27) (thickness 0.15)) (justify left))
    )
    (property "License" "Apache-2.0" (at 207.01 151.765 0)
      (effects (font (size 1.27 1.27) (thickness 0.15)) (justify left bottom) hide)
    )
    (property "Author" "Antmicro" (at 204.47 151.765 0)
      (effects (font (size 1.27 1.27) (thickness 0.15)) (justify left bottom) hide)
    )
    (property "Voltage" "" (at 201.93 151.765 0)
      (effects (font (size 1.27 1.27)) (justify left bottom) hide)
    )
    (property "Dielectric" "" (at 199.39 151.765 0)
      (effects (font (size 1.27 1.27)) (justify left bottom) hide)
    )
    (pin "1")
    (pin "2")
    (instances
      (project "data-center-rdimm-ddr4-tester"
        (path ""
          (reference "C102") (unit 1)
        )
      )
    )
  )

  (symbol (lib_id "antmicroCapacitors0402:C_100n_0402") (at 245.745 131.445 270) (unit 1)
    (in_bom yes) (on_board yes) (dnp no)
    (property "Reference" "C104" (at 246.38 132.08 90)
      (effects (font (size 1.524 1.524)) (justify left))
    )
    (property "Value" "C_100n_0402" (at 235.585 151.765 0)
      (effects (font (size 1.27 1.27) (thickness 0.15)) (justify left bottom) hide)
    )
    (property "Footprint" "antmicro-footprints:C_0402_1005Metric" (at 233.045 151.765 0)
      (effects (font (size 1.27 1.27) (thickness 0.15)) (justify left bottom) hide)
    )
    (property "Datasheet" "https://search.murata.co.jp/Ceramy/image/img/A01X/G101/ENG/GRM155R61H104KE14-01.pdf" (at 230.505 151.765 0)
      (effects (font (size 1.27 1.27) (thickness 0.15)) (justify left bottom) hide)
    )
    (property "Manufacturer" "Murata" (at 225.425 151.765 0)
      (effects (font (size 1.27 1.27) (thickness 0.15)) (justify left bottom) hide)
    )
    (property "MPN" "GRM155R61H104KE14D" (at 227.965 151.765 0)
      (effects (font (size 1.27 1.27) (thickness 0.15)) (justify left bottom) hide)
    )
    (property "Val" "100n" (at 246.38 135.89 90)
      (effects (font (size 1.27 1.27) (thickness 0.15)) (justify left))
    )
    (property "License" "Apache-2.0" (at 222.885 151.765 0)
      (effects (font (size 1.27 1.27) (thickness 0.15)) (justify left bottom) hide)
    )
    (property "Author" "Antmicro" (at 220.345 151.765 0)
      (effects (font (size 1.27 1.27) (thickness 0.15)) (justify left bottom) hide)
    )
    (property "Voltage" "50V" (at 217.805 151.765 0)
      (effects (font (size 1.27 1.27)) (justify left bottom) hide)
    )
    (property "Dielectric" "X5R" (at 215.265 151.765 0)
      (effects (font (size 1.27 1.27)) (justify left bottom) hide)
    )
    (pin "1")
    (pin "2")
    (instances
      (project "data-center-rdimm-ddr4-tester"
        (path ""
          (reference "C104") (unit 1)
        )
      )
    )
  )

  (symbol (lib_id "antmicropower:GND") (at 229.87 136.525 0) (unit 1)
    (in_bom yes) (on_board yes) (dnp no) (fields_autoplaced)
    (property "Reference" "#PWR0260" (at 229.87 142.875 0)
      (effects (font (size 1.27 1.27)) hide)
    )
    (property "Value" "GND" (at 229.87 140.97 0)
      (effects (font (size 1.27 1.27)))
    )
    (property "Footprint" "" (at 229.87 136.525 0)
      (effects (font (size 1.27 1.27)) hide)
    )
    (property "Datasheet" "" (at 229.87 136.525 0)
      (effects (font (size 1.27 1.27)) hide)
    )
    (property "Author" "Antmicro" (at 238.76 144.145 0)
      (effects (font (size 1.27 1.27) (thickness 0.15)) (justify left bottom) hide)
    )
    (property "License" "Apache-2.0" (at 238.76 146.685 0)
      (effects (font (size 1.27 1.27) (thickness 0.15)) (justify left bottom) hide)
    )
    (pin "1")
    (instances
      (project "data-center-rdimm-ddr4-tester"
        (path ""
          (reference "#PWR0260") (unit 1)
        )
      )
    )
  )

  (symbol (lib_id "antmicroResistors0402:R_10k_0402") (at 179.705 118.11 270) (unit 1)
    (in_bom yes) (on_board yes) (dnp no)
    (property "Reference" "R56" (at 177.8 119.3801 90)
      (effects (font (size 1.524 1.524)) (justify right))
    )
    (property "Value" "R_10k_0402" (at 167.005 138.43 0)
      (effects (font (size 1.27 1.27) (thickness 0.15)) (justify left bottom) hide)
    )
    (property "Footprint" "antmicro-footprints:R_0402_1005Metric" (at 164.465 138.43 0)
      (effects (font (size 1.27 1.27) (thickness 0.15)) (justify left bottom) hide)
    )
    (property "Datasheet" "https://www.bourns.com/docs/product-datasheets/cr.pdf" (at 161.925 138.43 0)
      (effects (font (size 1.27 1.27) (thickness 0.15)) (justify left bottom) hide)
    )
    (property "Manufacturer" "Bourns" (at 156.845 138.43 0)
      (effects (font (size 1.27 1.27) (thickness 0.15)) (justify left bottom) hide)
    )
    (property "MPN" "CR0402-FX-1002GLF" (at 159.385 138.43 0)
      (effects (font (size 1.27 1.27) (thickness 0.15)) (justify left bottom) hide)
    )
    (property "Val" "10k" (at 177.8 122.555 90)
      (effects (font (size 1.27 1.27) (thickness 0.15)) (justify right))
    )
    (property "License" "Apache-2.0" (at 154.305 138.43 0)
      (effects (font (size 1.27 1.27) (thickness 0.15)) (justify left bottom) hide)
    )
    (property "Author" "Antmicro" (at 151.765 138.43 0)
      (effects (font (size 1.27 1.27) (thickness 0.15)) (justify left bottom) hide)
    )
    (property "Tolerance" "1%" (at 169.545 138.43 0)
      (effects (font (size 1.27 1.27)) (justify left bottom) hide)
    )
    (pin "1")
    (pin "2")
    (instances
      (project "data-center-rdimm-ddr4-tester"
        (path ""
          (reference "R56") (unit 1)
        )
      )
    )
  )

  (symbol (lib_id "antmicropower:GND") (at 238.125 136.525 0) (unit 1)
    (in_bom yes) (on_board yes) (dnp no) (fields_autoplaced)
    (property "Reference" "#PWR0261" (at 238.125 142.875 0)
      (effects (font (size 1.27 1.27)) hide)
    )
    (property "Value" "GND" (at 238.125 140.97 0)
      (effects (font (size 1.27 1.27)))
    )
    (property "Footprint" "" (at 238.125 136.525 0)
      (effects (font (size 1.27 1.27)) hide)
    )
    (property "Datasheet" "" (at 238.125 136.525 0)
      (effects (font (size 1.27 1.27)) hide)
    )
    (property "Author" "Antmicro" (at 247.015 144.145 0)
      (effects (font (size 1.27 1.27) (thickness 0.15)) (justify left bottom) hide)
    )
    (property "License" "Apache-2.0" (at 247.015 146.685 0)
      (effects (font (size 1.27 1.27) (thickness 0.15)) (justify left bottom) hide)
    )
    (pin "1")
    (instances
      (project "data-center-rdimm-ddr4-tester"
        (path ""
          (reference "#PWR0261") (unit 1)
        )
      )
    )
  )

  (symbol (lib_id "antmicropower:GND") (at 245.745 136.525 0) (unit 1)
    (in_bom yes) (on_board yes) (dnp no) (fields_autoplaced)
    (property "Reference" "#PWR0262" (at 245.745 142.875 0)
      (effects (font (size 1.27 1.27)) hide)
    )
    (property "Value" "GND" (at 245.745 140.97 0)
      (effects (font (size 1.27 1.27)))
    )
    (property "Footprint" "" (at 245.745 136.525 0)
      (effects (font (size 1.27 1.27)) hide)
    )
    (property "Datasheet" "" (at 245.745 136.525 0)
      (effects (font (size 1.27 1.27)) hide)
    )
    (property "Author" "Antmicro" (at 254.635 144.145 0)
      (effects (font (size 1.27 1.27) (thickness 0.15)) (justify left bottom) hide)
    )
    (property "License" "Apache-2.0" (at 254.635 146.685 0)
      (effects (font (size 1.27 1.27) (thickness 0.15)) (justify left bottom) hide)
    )
    (pin "1")
    (instances
      (project "data-center-rdimm-ddr4-tester"
        (path ""
          (reference "#PWR0262") (unit 1)
        )
      )
    )
  )

  (symbol (lib_id "antmicroCapacitors0402:C_100n_0402") (at 238.125 131.445 270) (unit 1)
    (in_bom yes) (on_board yes) (dnp no)
    (property "Reference" "C103" (at 238.76 132.08 90)
      (effects (font (size 1.524 1.524)) (justify left))
    )
    (property "Value" "C_100n_0402" (at 227.965 151.765 0)
      (effects (font (size 1.27 1.27) (thickness 0.15)) (justify left bottom) hide)
    )
    (property "Footprint" "antmicro-footprints:C_0402_1005Metric" (at 225.425 151.765 0)
      (effects (font (size 1.27 1.27) (thickness 0.15)) (justify left bottom) hide)
    )
    (property "Datasheet" "https://search.murata.co.jp/Ceramy/image/img/A01X/G101/ENG/GRM155R61H104KE14-01.pdf" (at 222.885 151.765 0)
      (effects (font (size 1.27 1.27) (thickness 0.15)) (justify left bottom) hide)
    )
    (property "Manufacturer" "Murata" (at 217.805 151.765 0)
      (effects (font (size 1.27 1.27) (thickness 0.15)) (justify left bottom) hide)
    )
    (property "MPN" "GRM155R61H104KE14D" (at 220.345 151.765 0)
      (effects (font (size 1.27 1.27) (thickness 0.15)) (justify left bottom) hide)
    )
    (property "Val" "100n" (at 238.76 135.89 90)
      (effects (font (size 1.27 1.27) (thickness 0.15)) (justify left))
    )
    (property "License" "Apache-2.0" (at 215.265 151.765 0)
      (effects (font (size 1.27 1.27) (thickness 0.15)) (justify left bottom) hide)
    )
    (property "Author" "Antmicro" (at 212.725 151.765 0)
      (effects (font (size 1.27 1.27) (thickness 0.15)) (justify left bottom) hide)
    )
    (property "Voltage" "50V" (at 210.185 151.765 0)
      (effects (font (size 1.27 1.27)) (justify left bottom) hide)
    )
    (property "Dielectric" "X5R" (at 207.645 151.765 0)
      (effects (font (size 1.27 1.27)) (justify left bottom) hide)
    )
    (pin "1")
    (pin "2")
    (instances
      (project "data-center-rdimm-ddr4-tester"
        (path ""
          (reference "C103") (unit 1)
        )
      )
    )
  )

  (symbol (lib_id "antmicroResistors0402:R_10k_0402") (at 182.88 118.11 270) (unit 1)
    (in_bom yes) (on_board yes) (dnp no) (fields_autoplaced)
    (property "Reference" "R61" (at 184.785 119.38 90)
      (effects (font (size 1.524 1.524)) (justify left))
    )
    (property "Value" "R_10k_0402" (at 170.18 138.43 0)
      (effects (font (size 1.27 1.27) (thickness 0.15)) (justify left bottom) hide)
    )
    (property "Footprint" "antmicro-footprints:R_0402_1005Metric" (at 167.64 138.43 0)
      (effects (font (size 1.27 1.27) (thickness 0.15)) (justify left bottom) hide)
    )
    (property "Datasheet" "https://www.bourns.com/docs/product-datasheets/cr.pdf" (at 165.1 138.43 0)
      (effects (font (size 1.27 1.27) (thickness 0.15)) (justify left bottom) hide)
    )
    (property "Manufacturer" "Bourns" (at 160.02 138.43 0)
      (effects (font (size 1.27 1.27) (thickness 0.15)) (justify left bottom) hide)
    )
    (property "MPN" "CR0402-FX-1002GLF" (at 162.56 138.43 0)
      (effects (font (size 1.27 1.27) (thickness 0.15)) (justify left bottom) hide)
    )
    (property "Val" "10k" (at 184.785 122.5549 90)
      (effects (font (size 1.27 1.27) (thickness 0.15)) (justify left))
    )
    (property "License" "Apache-2.0" (at 157.48 138.43 0)
      (effects (font (size 1.27 1.27) (thickness 0.15)) (justify left bottom) hide)
    )
    (property "Author" "Antmicro" (at 154.94 138.43 0)
      (effects (font (size 1.27 1.27) (thickness 0.15)) (justify left bottom) hide)
    )
    (property "Tolerance" "1%" (at 172.72 138.43 0)
      (effects (font (size 1.27 1.27)) (justify left bottom) hide)
    )
    (pin "1")
    (pin "2")
    (instances
      (project "data-center-rdimm-ddr4-tester"
        (path ""
          (reference "R61") (unit 1)
        )
      )
    )
  )

  (symbol (lib_id "antmicropower:GND") (at 223.52 166.37 0) (unit 1)
    (in_bom yes) (on_board yes) (dnp no) (fields_autoplaced)
    (property "Reference" "#PWR0263" (at 223.52 172.72 0)
      (effects (font (size 1.27 1.27)) hide)
    )
    (property "Value" "GND" (at 223.52 171.45 0)
      (effects (font (size 1.27 1.27)))
    )
    (property "Footprint" "" (at 223.52 166.37 0)
      (effects (font (size 1.27 1.27)) hide)
    )
    (property "Datasheet" "" (at 223.52 166.37 0)
      (effects (font (size 1.27 1.27)) hide)
    )
    (property "Author" "Antmicro" (at 232.41 173.99 0)
      (effects (font (size 1.27 1.27) (thickness 0.15)) (justify left bottom) hide)
    )
    (property "License" "Apache-2.0" (at 232.41 176.53 0)
      (effects (font (size 1.27 1.27) (thickness 0.15)) (justify left bottom) hide)
    )
    (pin "1")
    (instances
      (project "data-center-rdimm-ddr4-tester"
        (path ""
          (reference "#PWR0263") (unit 1)
        )
      )
    )
  )

  (symbol (lib_id "antmicroCapacitors0402:C_100n_0402") (at 253.365 131.445 270) (unit 1)
    (in_bom yes) (on_board yes) (dnp no)
    (property "Reference" "C105" (at 254 132.08 90)
      (effects (font (size 1.524 1.524)) (justify left))
    )
    (property "Value" "C_100n_0402" (at 243.205 151.765 0)
      (effects (font (size 1.27 1.27) (thickness 0.15)) (justify left bottom) hide)
    )
    (property "Footprint" "antmicro-footprints:C_0402_1005Metric" (at 240.665 151.765 0)
      (effects (font (size 1.27 1.27) (thickness 0.15)) (justify left bottom) hide)
    )
    (property "Datasheet" "https://search.murata.co.jp/Ceramy/image/img/A01X/G101/ENG/GRM155R61H104KE14-01.pdf" (at 238.125 151.765 0)
      (effects (font (size 1.27 1.27) (thickness 0.15)) (justify left bottom) hide)
    )
    (property "Manufacturer" "Murata" (at 233.045 151.765 0)
      (effects (font (size 1.27 1.27) (thickness 0.15)) (justify left bottom) hide)
    )
    (property "MPN" "GRM155R61H104KE14D" (at 235.585 151.765 0)
      (effects (font (size 1.27 1.27) (thickness 0.15)) (justify left bottom) hide)
    )
    (property "Val" "100n" (at 254 135.89 90)
      (effects (font (size 1.27 1.27) (thickness 0.15)) (justify left))
    )
    (property "License" "Apache-2.0" (at 230.505 151.765 0)
      (effects (font (size 1.27 1.27) (thickness 0.15)) (justify left bottom) hide)
    )
    (property "Author" "Antmicro" (at 227.965 151.765 0)
      (effects (font (size 1.27 1.27) (thickness 0.15)) (justify left bottom) hide)
    )
    (property "Voltage" "50V" (at 225.425 151.765 0)
      (effects (font (size 1.27 1.27)) (justify left bottom) hide)
    )
    (property "Dielectric" "X5R" (at 222.885 151.765 0)
      (effects (font (size 1.27 1.27)) (justify left bottom) hide)
    )
    (pin "1")
    (pin "2")
    (instances
      (project "data-center-rdimm-ddr4-tester"
        (path ""
          (reference "C105") (unit 1)
        )
      )
    )
  )

  (symbol (lib_id "antmicropower:GND") (at 253.365 136.525 0) (unit 1)
    (in_bom yes) (on_board yes) (dnp no) (fields_autoplaced)
    (property "Reference" "#PWR0264" (at 253.365 142.875 0)
      (effects (font (size 1.27 1.27)) hide)
    )
    (property "Value" "GND" (at 253.365 140.97 0)
      (effects (font (size 1.27 1.27)))
    )
    (property "Footprint" "" (at 253.365 136.525 0)
      (effects (font (size 1.27 1.27)) hide)
    )
    (property "Datasheet" "" (at 253.365 136.525 0)
      (effects (font (size 1.27 1.27)) hide)
    )
    (property "Author" "Antmicro" (at 262.255 144.145 0)
      (effects (font (size 1.27 1.27) (thickness 0.15)) (justify left bottom) hide)
    )
    (property "License" "Apache-2.0" (at 262.255 146.685 0)
      (effects (font (size 1.27 1.27) (thickness 0.15)) (justify left bottom) hide)
    )
    (pin "1")
    (instances
      (project "data-center-rdimm-ddr4-tester"
        (path ""
          (reference "#PWR0264") (unit 1)
        )
      )
    )
  )
)
